(kicad_pcb
	(version 20260206)
	(generator "pcbnew")
	(generator_version "10.0")
	(general
		(thickness 1.6)
		(legacy_teardrops no)
	)
	(paper "A4")
	(title_block
		(title "04192023_DAF0TMB3IC0_F0TG_MB_C_brd_V02_OCP.brd")
		(comment 1 "Grand Teton / footprints 7480-7487 of 8354")
	)
	(layers
		(0 "F.Cu" signal "TOP")
		(4 "In1.Cu" signal "GND")
		(6 "In2.Cu" signal "IN1")
		(8 "In3.Cu" signal "GND1")
		(10 "In4.Cu" signal "IN2")
		(12 "In5.Cu" signal "GND2")
		(14 "In6.Cu" signal "IN3")
		(16 "In7.Cu" signal "GND3")
		(18 "In8.Cu" signal "VCC")
		(20 "In9.Cu" signal "VCC1")
		(22 "In10.Cu" signal "GND4")
		(24 "In11.Cu" signal "IN4")
		(26 "In12.Cu" signal "GND5")
		(28 "In13.Cu" signal "IN5")
		(30 "In14.Cu" signal "GND6")
		(32 "In15.Cu" signal "IN6")
		(34 "In16.Cu" signal "GND7")
		(2 "B.Cu" signal "BOTTOM")
		(9 "F.Adhes" user "F.Adhesive")
		(11 "B.Adhes" user "B.Adhesive")
		(13 "F.Paste" user "Package Geometry/Pastemask Top")
		(15 "B.Paste" user "Package Geometry/Pastemask Bottom")
		(5 "F.SilkS" user "Ref Des/Silkscreen Top")
		(7 "B.SilkS" user "Ref Des/Silkscreen Bottom")
		(1 "F.Mask" user "Board Geometry/Soldermask Top")
		(3 "B.Mask" user "Board Geometry/Soldermask Bottom")
		(17 "Dwgs.User" user "User.Drawings")
		(19 "Cmts.User" user "User.Comments")
		(21 "Eco1.User" user "User.Eco1")
		(23 "Eco2.User" user "User.Eco2")
		(25 "Edge.Cuts" user "Board Geometry/Outline")
		(27 "Margin" user)
		(31 "F.CrtYd" user "Package Geometry/Place Bound Top")
		(29 "B.CrtYd" user "Package Geometry/Place Bound Bottom")
		(35 "F.Fab" user "Ref Des/Assembly Top")
		(33 "B.Fab" user "Ref Des/Assembly Bottom")
	)
	(footprint ""
		(layer "B.Cu")
		(at 351.389188 -158.474156 90)
		(property "Reference" "PR433"
			(at 0 0 90)
			(layer "B.SilkS")
			(hide yes)
			(effects
				(font
					(size 1.27 1.27)
				)
				(justify mirror)
			)
		)
		(property "Value" ""
			(at 0 0 90)
			(layer "B.Fab")
			(effects
				(font
					(size 1.27 1.27)
				)
				(justify mirror)
			)
		)
		(duplicate_pad_numbers_are_jumpers no)
		(fp_line
			(start 0.7874 -0.4064)
			(end -0.7874 -0.4064)
			(stroke
				(width 0.1524)
				(type default)
			)
			(layer "B.SilkS")
		)
		(fp_line
			(start -0.7874 -0.4064)
			(end -0.7874 0.4064)
			(stroke
				(width 0.1524)
				(type default)
			)
			(layer "B.SilkS")
		)
		(fp_line
			(start 0.7874 0.4064)
			(end 0.7874 -0.4064)
			(stroke
				(width 0.1524)
				(type default)
			)
			(layer "B.SilkS")
		)
		(fp_line
			(start -0.7874 0.4064)
			(end 0.7874 0.4064)
			(stroke
				(width 0.1524)
				(type default)
			)
			(layer "B.SilkS")
		)
		(fp_line
			(start 0.67945 -0.305054)
			(end 0.12065 -0.305054)
			(stroke
				(width 0.1)
				(type default)
			)
			(layer "B.Fab")
		)
		(fp_line
			(start 0.12065 -0.305054)
			(end 0.12065 -0.2794)
			(stroke
				(width 0.1)
				(type default)
			)
			(layer "B.Fab")
		)
		(fp_line
			(start -0.12065 -0.3048)
			(end -0.67945 -0.3048)
			(stroke
				(width 0.1)
				(type default)
			)
			(layer "B.Fab")
		)
		(fp_line
			(start -0.67945 -0.3048)
			(end -0.67945 0.3048)
			(stroke
				(width 0.1)
				(type default)
			)
			(layer "B.Fab")
		)
		(fp_line
			(start 0.12065 -0.2794)
			(end -0.12065 -0.2794)
			(stroke
				(width 0.1)
				(type default)
			)
			(layer "B.Fab")
		)
		(fp_line
			(start -0.12065 -0.2794)
			(end -0.12065 -0.3048)
			(stroke
				(width 0.1)
				(type default)
			)
			(layer "B.Fab")
		)
		(fp_line
			(start 0.12065 0.2794)
			(end 0.12065 0.3048)
			(stroke
				(width 0.1)
				(type default)
			)
			(layer "B.Fab")
		)
		(fp_line
			(start -0.120396 0.2794)
			(end 0.12065 0.2794)
			(stroke
				(width 0.1)
				(type default)
			)
			(layer "B.Fab")
		)
		(fp_line
			(start 0.67945 0.3048)
			(end 0.67945 -0.305054)
			(stroke
				(width 0.1)
				(type default)
			)
			(layer "B.Fab")
		)
		(fp_line
			(start 0.12065 0.3048)
			(end 0.67945 0.3048)
			(stroke
				(width 0.1)
				(type default)
			)
			(layer "B.Fab")
		)
		(fp_line
			(start -0.120396 0.3048)
			(end -0.120396 0.2794)
			(stroke
				(width 0.1)
				(type default)
			)
			(layer "B.Fab")
		)
		(fp_line
			(start -0.67945 0.3048)
			(end -0.120396 0.3048)
			(stroke
				(width 0.1)
				(type default)
			)
			(layer "B.Fab")
		)
		(pad "1" smd circle
			(at 0.40005 0 270)
			(size 0 0)
			(layers "B.Cu" "B.Mask" "B.Paste")
			(net "PVDDCR_CPU0_P0_VOS6")
		)
		(pad "2" smd circle
			(at -0.40005 0 270)
			(size 0 0)
			(layers "B.Cu" "B.Mask" "B.Paste")
			(net "PVDDCR_CPU0_P0")
		)
	)
	(footprint ""
		(layer "B.Cu")
		(at 31.891732 -337.989672 -90)
		(property "Reference" "PC636_4"
			(at 0 0 90)
			(layer "B.SilkS")
			(hide yes)
			(effects
				(font
					(size 1.27 1.27)
				)
				(justify mirror)
			)
		)
		(property "Value" ""
			(at 0 0 90)
			(layer "B.Fab")
			(effects
				(font
					(size 1.27 1.27)
				)
				(justify mirror)
			)
		)
		(duplicate_pad_numbers_are_jumpers no)
		(fp_line
			(start -1.524 0.762)
			(end 1.524 0.762)
			(stroke
				(width 0.1524)
				(type default)
			)
			(layer "B.SilkS")
		)
		(fp_line
			(start 1.524 0.762)
			(end 1.524 -0.762)
			(stroke
				(width 0.1524)
				(type default)
			)
			(layer "B.SilkS")
		)
		(fp_line
			(start -1.524 -0.762)
			(end -1.524 0.762)
			(stroke
				(width 0.1524)
				(type default)
			)
			(layer "B.SilkS")
		)
		(fp_line
			(start 1.524 -0.762)
			(end -1.524 -0.762)
			(stroke
				(width 0.1524)
				(type default)
			)
			(layer "B.SilkS")
		)
		(fp_line
			(start -1.1049 0.724916)
			(end -1.1049 -0.724916)
			(stroke
				(width 0.1)
				(type default)
			)
			(layer "B.Fab")
		)
		(fp_line
			(start 1.1049 0.724916)
			(end -1.1049 0.724916)
			(stroke
				(width 0.1)
				(type default)
			)
			(layer "B.Fab")
		)
		(fp_line
			(start -1.1049 -0.724916)
			(end 1.1049 -0.724916)
			(stroke
				(width 0.1)
				(type default)
			)
			(layer "B.Fab")
		)
		(fp_line
			(start 1.1049 -0.724916)
			(end 1.1049 0.724916)
			(stroke
				(width 0.1)
				(type default)
			)
			(layer "B.Fab")
		)
		(pad "1" smd rect
			(at 0.889 0 270)
			(size 1.016 1.27)
			(layers "B.Cu" "B.Mask" "B.Paste")
			(net "PVDDIO_P1")
		)
		(pad "2" smd rect
			(at -0.889 0 270)
			(size 1.016 1.27)
			(layers "B.Cu" "B.Mask" "B.Paste")
			(net "GND")
		)
	)
	(footprint ""
		(layer "B.Cu")
		(at 167.772334 -193.996564)
		(property "Reference" "C160"
			(at 0 0 0)
			(layer "B.SilkS")
			(hide yes)
			(effects
				(font
					(size 1.27 1.27)
				)
				(justify mirror)
			)
		)
		(property "Value" ""
			(at 0 0 0)
			(layer "B.Fab")
			(effects
				(font
					(size 1.27 1.27)
				)
				(justify mirror)
			)
		)
		(duplicate_pad_numbers_are_jumpers no)
		(fp_line
			(start -0.7874 -0.4064)
			(end -0.7874 0.4064)
			(stroke
				(width 0.1524)
				(type default)
			)
			(layer "B.SilkS")
		)
		(fp_line
			(start -0.7874 0.4064)
			(end 0.7874 0.4064)
			(stroke
				(width 0.1524)
				(type default)
			)
			(layer "B.SilkS")
		)
		(fp_line
			(start 0.7874 -0.4064)
			(end -0.7874 -0.4064)
			(stroke
				(width 0.1524)
				(type default)
			)
			(layer "B.SilkS")
		)
		(fp_line
			(start 0.7874 0.4064)
			(end 0.7874 -0.4064)
			(stroke
				(width 0.1524)
				(type default)
			)
			(layer "B.SilkS")
		)
		(fp_line
			(start -0.67945 -0.3048)
			(end -0.67945 0.3048)
			(stroke
				(width 0.1)
				(type default)
			)
			(layer "B.Fab")
		)
		(fp_line
			(start -0.67945 0.3048)
			(end -0.120396 0.3048)
			(stroke
				(width 0.1)
				(type default)
			)
			(layer "B.Fab")
		)
		(fp_line
			(start -0.12065 -0.3048)
			(end -0.67945 -0.3048)
			(stroke
				(width 0.1)
				(type default)
			)
			(layer "B.Fab")
		)
		(fp_line
			(start -0.12065 -0.2794)
			(end -0.12065 -0.3048)
			(stroke
				(width 0.1)
				(type default)
			)
			(layer "B.Fab")
		)
		(fp_line
			(start -0.120396 0.2794)
			(end 0.12065 0.2794)
			(stroke
				(width 0.1)
				(type default)
			)
			(layer "B.Fab")
		)
		(fp_line
			(start -0.120396 0.3048)
			(end -0.120396 0.2794)
			(stroke
				(width 0.1)
				(type default)
			)
			(layer "B.Fab")
		)
		(fp_line
			(start 0.12065 -0.305054)
			(end 0.12065 -0.2794)
			(stroke
				(width 0.1)
				(type default)
			)
			(layer "B.Fab")
		)
		(fp_line
			(start 0.12065 -0.2794)
			(end -0.12065 -0.2794)
			(stroke
				(width 0.1)
				(type default)
			)
			(layer "B.Fab")
		)
		(fp_line
			(start 0.12065 0.2794)
			(end 0.12065 0.3048)
			(stroke
				(width 0.1)
				(type default)
			)
			(layer "B.Fab")
		)
		(fp_line
			(start 0.12065 0.3048)
			(end 0.67945 0.3048)
			(stroke
				(width 0.1)
				(type default)
			)
			(layer "B.Fab")
		)
		(fp_line
			(start 0.67945 -0.305054)
			(end 0.12065 -0.305054)
			(stroke
				(width 0.1)
				(type default)
			)
			(layer "B.Fab")
		)
		(fp_line
			(start 0.67945 0.3048)
			(end 0.67945 -0.305054)
			(stroke
				(width 0.1)
				(type default)
			)
			(layer "B.Fab")
		)
		(pad "1" smd circle
			(at 0.40005 0 180)
			(size 0 0)
			(layers "B.Cu" "B.Mask" "B.Paste")
			(net "P3V3_AUX")
		)
		(pad "2" smd circle
			(at -0.40005 0 180)
			(size 0 0)
			(layers "B.Cu" "B.Mask" "B.Paste")
			(net "GND")
		)
	)
	(footprint ""
		(layer "B.Cu")
		(at 80.937354 -178.962812 90)
		(property "Reference" "PC264_1"
			(at 0 0 90)
			(layer "B.SilkS")
			(hide yes)
			(effects
				(font
					(size 1.27 1.27)
				)
				(justify mirror)
			)
		)
		(property "Value" ""
			(at 0 0 90)
			(layer "B.Fab")
			(effects
				(font
					(size 1.27 1.27)
				)
				(justify mirror)
			)
		)
		(duplicate_pad_numbers_are_jumpers no)
		(fp_line
			(start 1.524 -0.762)
			(end -1.524 -0.762)
			(stroke
				(width 0.1524)
				(type default)
			)
			(layer "B.SilkS")
		)
		(fp_line
			(start -1.524 -0.762)
			(end -1.524 0.762)
			(stroke
				(width 0.1524)
				(type default)
			)
			(layer "B.SilkS")
		)
		(fp_line
			(start 1.524 0.762)
			(end 1.524 -0.762)
			(stroke
				(width 0.1524)
				(type default)
			)
			(layer "B.SilkS")
		)
		(fp_line
			(start -1.524 0.762)
			(end 1.524 0.762)
			(stroke
				(width 0.1524)
				(type default)
			)
			(layer "B.SilkS")
		)
		(fp_line
			(start 1.1049 -0.724916)
			(end 1.1049 0.724916)
			(stroke
				(width 0.1)
				(type default)
			)
			(layer "B.Fab")
		)
		(fp_line
			(start -1.1049 -0.724916)
			(end 1.1049 -0.724916)
			(stroke
				(width 0.1)
				(type default)
			)
			(layer "B.Fab")
		)
		(fp_line
			(start 1.1049 0.724916)
			(end -1.1049 0.724916)
			(stroke
				(width 0.1)
				(type default)
			)
			(layer "B.Fab")
		)
		(fp_line
			(start -1.1049 0.724916)
			(end -1.1049 -0.724916)
			(stroke
				(width 0.1)
				(type default)
			)
			(layer "B.Fab")
		)
		(pad "1" smd rect
			(at 0.889 0 90)
			(size 1.016 1.27)
			(layers "B.Cu" "B.Mask" "B.Paste")
			(net "SW_P12V_AUX_PVDDCR_CPU0_P1_FLT")
		)
		(pad "2" smd rect
			(at -0.889 0 90)
			(size 1.016 1.27)
			(layers "B.Cu" "B.Mask" "B.Paste")
			(net "GND")
		)
	)
	(footprint ""
		(layer "B.Cu")
		(at 125.590046 -408.517344 90)
		(property "Reference" "C6732"
			(at 0 0 90)
			(layer "B.SilkS")
			(hide yes)
			(effects
				(font
					(size 1.27 1.27)
				)
				(justify mirror)
			)
		)
		(property "Value" ""
			(at 0 0 90)
			(layer "B.Fab")
			(effects
				(font
					(size 1.27 1.27)
				)
				(justify mirror)
			)
		)
		(duplicate_pad_numbers_are_jumpers no)
		(fp_line
			(start 0.299974 -0.150114)
			(end -0.299974 -0.150114)
			(stroke
				(width 0.1)
				(type default)
			)
			(layer "B.Fab")
		)
		(fp_line
			(start -0.299974 -0.150114)
			(end -0.299974 0.150114)
			(stroke
				(width 0.1)
				(type default)
			)
			(layer "B.Fab")
		)
		(fp_line
			(start 0.299974 0.150114)
			(end 0.299974 -0.150114)
			(stroke
				(width 0.1)
				(type default)
			)
			(layer "B.Fab")
		)
		(fp_line
			(start -0.299974 0.150114)
			(end 0.299974 0.150114)
			(stroke
				(width 0.1)
				(type default)
			)
			(layer "B.Fab")
		)
		(pad "1" smd rect
			(at 0.2667 0 270)
			(size 0.3048 0.381)
			(layers "B.Cu" "B.Mask" "B.Paste")
			(net "P5E_CPU1_P3_TX_BUF_C_DN<3>")
		)
		(pad "2" smd rect
			(at -0.2667 0 270)
			(size 0.3048 0.381)
			(layers "B.Cu" "B.Mask" "B.Paste")
			(net "P5E_CPU1_P3_TX_BUF_DN<3>")
		)
	)
	(footprint ""
		(layer "B.Cu")
		(at 369.57 -426.466)
		(property "Reference" "C1057"
			(at 0 0 0)
			(layer "B.SilkS")
			(hide yes)
			(effects
				(font
					(size 1.27 1.27)
				)
				(justify mirror)
			)
		)
		(property "Value" ""
			(at 0 0 0)
			(layer "B.Fab")
			(effects
				(font
					(size 1.27 1.27)
				)
				(justify mirror)
			)
		)
		(duplicate_pad_numbers_are_jumpers no)
		(fp_line
			(start -0.299974 -0.150114)
			(end -0.299974 0.150114)
			(stroke
				(width 0.1)
				(type default)
			)
			(layer "B.Fab")
		)
		(fp_line
			(start -0.299974 0.150114)
			(end 0.299974 0.150114)
			(stroke
				(width 0.1)
				(type default)
			)
			(layer "B.Fab")
		)
		(fp_line
			(start 0.299974 -0.150114)
			(end -0.299974 -0.150114)
			(stroke
				(width 0.1)
				(type default)
			)
			(layer "B.Fab")
		)
		(fp_line
			(start 0.299974 0.150114)
			(end 0.299974 -0.150114)
			(stroke
				(width 0.1)
				(type default)
			)
			(layer "B.Fab")
		)
		(pad "1" smd rect
			(at 0.2667 0 180)
			(size 0.3048 0.381)
			(layers "B.Cu" "B.Mask" "B.Paste")
			(net "P1V8_CPU0_RT_1D")
		)
		(pad "2" smd rect
			(at -0.2667 0 180)
			(size 0.3048 0.381)
			(layers "B.Cu" "B.Mask" "B.Paste")
			(net "GND")
		)
	)
	(footprint ""
		(layer "B.Cu")
		(at 331.39761 -337.638898 -90)
		(property "Reference" "PR84"
			(at 0 0 90)
			(layer "B.SilkS")
			(hide yes)
			(effects
				(font
					(size 1.27 1.27)
				)
				(justify mirror)
			)
		)
		(property "Value" ""
			(at 0 0 90)
			(layer "B.Fab")
			(effects
				(font
					(size 1.27 1.27)
				)
				(justify mirror)
			)
		)
		(duplicate_pad_numbers_are_jumpers no)
		(fp_line
			(start -0.7874 0.4064)
			(end 0.7874 0.4064)
			(stroke
				(width 0.1524)
				(type default)
			)
			(layer "B.SilkS")
		)
		(fp_line
			(start 0.7874 0.4064)
			(end 0.7874 -0.4064)
			(stroke
				(width 0.1524)
				(type default)
			)
			(layer "B.SilkS")
		)
		(fp_line
			(start -0.7874 -0.4064)
			(end -0.7874 0.4064)
			(stroke
				(width 0.1524)
				(type default)
			)
			(layer "B.SilkS")
		)
		(fp_line
			(start 0.7874 -0.4064)
			(end -0.7874 -0.4064)
			(stroke
				(width 0.1524)
				(type default)
			)
			(layer "B.SilkS")
		)
		(fp_line
			(start -0.67945 0.3048)
			(end -0.120396 0.3048)
			(stroke
				(width 0.1)
				(type default)
			)
			(layer "B.Fab")
		)
		(fp_line
			(start -0.120396 0.3048)
			(end -0.120396 0.2794)
			(stroke
				(width 0.1)
				(type default)
			)
			(layer "B.Fab")
		)
		(fp_line
			(start 0.12065 0.3048)
			(end 0.67945 0.3048)
			(stroke
				(width 0.1)
				(type default)
			)
			(layer "B.Fab")
		)
		(fp_line
			(start 0.67945 0.3048)
			(end 0.67945 -0.305054)
			(stroke
				(width 0.1)
				(type default)
			)
			(layer "B.Fab")
		)
		(fp_line
			(start -0.120396 0.2794)
			(end 0.12065 0.2794)
			(stroke
				(width 0.1)
				(type default)
			)
			(layer "B.Fab")
		)
		(fp_line
			(start 0.12065 0.2794)
			(end 0.12065 0.3048)
			(stroke
				(width 0.1)
				(type default)
			)
			(layer "B.Fab")
		)
		(fp_line
			(start -0.12065 -0.2794)
			(end -0.12065 -0.3048)
			(stroke
				(width 0.1)
				(type default)
			)
			(layer "B.Fab")
		)
		(fp_line
			(start 0.12065 -0.2794)
			(end -0.12065 -0.2794)
			(stroke
				(width 0.1)
				(type default)
			)
			(layer "B.Fab")
		)
		(fp_line
			(start -0.67945 -0.3048)
			(end -0.67945 0.3048)
			(stroke
				(width 0.1)
				(type default)
			)
			(layer "B.Fab")
		)
		(fp_line
			(start -0.12065 -0.3048)
			(end -0.67945 -0.3048)
			(stroke
				(width 0.1)
				(type default)
			)
			(layer "B.Fab")
		)
		(fp_line
			(start 0.12065 -0.305054)
			(end 0.12065 -0.2794)
			(stroke
				(width 0.1)
				(type default)
			)
			(layer "B.Fab")
		)
		(fp_line
			(start 0.67945 -0.305054)
			(end 0.12065 -0.305054)
			(stroke
				(width 0.1)
				(type default)
			)
			(layer "B.Fab")
		)
		(pad "1" smd circle
			(at 0.40005 0 90)
			(size 0 0)
			(layers "B.Cu" "B.Mask" "B.Paste")
			(net "PVDDCR_CPU1_P0_VOS1")
		)
		(pad "2" smd circle
			(at -0.40005 0 90)
			(size 0 0)
			(layers "B.Cu" "B.Mask" "B.Paste")
			(net "PVDDCR_CPU1_P0")
		)
	)
	(footprint ""
		(layer "B.Cu")
		(at 115.277138 -261.748016 90)
		(property "Reference" "C2497"
			(at 0 0 90)
			(layer "B.SilkS")
			(hide yes)
			(effects
				(font
					(size 1.27 1.27)
				)
				(justify mirror)
			)
		)
		(property "Value" ""
			(at 0 0 90)
			(layer "B.Fab")
			(effects
				(font
					(size 1.27 1.27)
				)
				(justify mirror)
			)
		)
		(duplicate_pad_numbers_are_jumpers no)
		(fp_line
			(start 0.7874 -0.4064)
			(end -0.7874 -0.4064)
			(stroke
				(width 0.1524)
				(type default)
			)
			(layer "B.SilkS")
		)
		(fp_line
			(start -0.7874 -0.4064)
			(end -0.7874 0.4064)
			(stroke
				(width 0.1524)
				(type default)
			)
			(layer "B.SilkS")
		)
		(fp_line
			(start 0.7874 0.4064)
			(end 0.7874 -0.4064)
			(stroke
				(width 0.1524)
				(type default)
			)
			(layer "B.SilkS")
		)
		(fp_line
			(start -0.7874 0.4064)
			(end 0.7874 0.4064)
			(stroke
				(width 0.1524)
				(type default)
			)
			(layer "B.SilkS")
		)
		(fp_line
			(start 0.67945 -0.305054)
			(end 0.12065 -0.305054)
			(stroke
				(width 0.1)
				(type default)
			)
			(layer "B.Fab")
		)
		(fp_line
			(start 0.12065 -0.305054)
			(end 0.12065 -0.2794)
			(stroke
				(width 0.1)
				(type default)
			)
			(layer "B.Fab")
		)
		(fp_line
			(start -0.12065 -0.3048)
			(end -0.67945 -0.3048)
			(stroke
				(width 0.1)
				(type default)
			)
			(layer "B.Fab")
		)
		(fp_line
			(start -0.67945 -0.3048)
			(end -0.67945 0.3048)
			(stroke
				(width 0.1)
				(type default)
			)
			(layer "B.Fab")
		)
		(fp_line
			(start 0.12065 -0.2794)
			(end -0.12065 -0.2794)
			(stroke
				(width 0.1)
				(type default)
			)
			(layer "B.Fab")
		)
		(fp_line
			(start -0.12065 -0.2794)
			(end -0.12065 -0.3048)
			(stroke
				(width 0.1)
				(type default)
			)
			(layer "B.Fab")
		)
		(fp_line
			(start 0.12065 0.2794)
			(end 0.12065 0.3048)
			(stroke
				(width 0.1)
				(type default)
			)
			(layer "B.Fab")
		)
		(fp_line
			(start -0.120396 0.2794)
			(end 0.12065 0.2794)
			(stroke
				(width 0.1)
				(type default)
			)
			(layer "B.Fab")
		)
		(fp_line
			(start 0.67945 0.3048)
			(end 0.67945 -0.305054)
			(stroke
				(width 0.1)
				(type default)
			)
			(layer "B.Fab")
		)
		(fp_line
			(start 0.12065 0.3048)
			(end 0.67945 0.3048)
			(stroke
				(width 0.1)
				(type default)
			)
			(layer "B.Fab")
		)
		(fp_line
			(start -0.120396 0.3048)
			(end -0.120396 0.2794)
			(stroke
				(width 0.1)
				(type default)
			)
			(layer "B.Fab")
		)
		(fp_line
			(start -0.67945 0.3048)
			(end -0.120396 0.3048)
			(stroke
				(width 0.1)
				(type default)
			)
			(layer "B.Fab")
		)
		(pad "1" smd circle
			(at 0.40005 0 270)
			(size 0 0)
			(layers "B.Cu" "B.Mask" "B.Paste")
			(net "PVDD11_S3_P1")
		)
		(pad "2" smd circle
			(at -0.40005 0 270)
			(size 0 0)
			(layers "B.Cu" "B.Mask" "B.Paste")
			(net "GND")
		)
	)
)
